# T6G (Grand Teton) — schematic netlist excerpt (pin names and nets, part order shuffled) for the footprints in the layout excerpt that follows; sources: Cadence DE-HDL packaged netlist, KiCad conversion of 04192023_DAF0TMB3IC0_F0TG_MB_C_brd_V02_OCP.brd

U14  SN74AUC2G66DCTR  IC  pkg SSOP8  page 174
  \1a\  = JTAG_CPU0_TDO_CPU1_TDI
  \1b\  = JTAG_CPU1_R_TDI
  \2c\  = FM_PLD_CPU1_PRSNT_HDT_N
  GND  = GND
  \2a\  = JTAG_CPU0_TDO_CPU1_TDI
  \2b\  = JTAG_CPU1_BYPASS
  \1c\  = CPU1_HDT_BYPASS_SEL
  VCC  = PVDD18_S5_P0

(kicad_pcb
	(version 20260206)
	(generator "pcbnew")
	(generator_version "10.0")
	(general
		(thickness 1.6)
		(legacy_teardrops no)
	)
	(paper "A4")
	(title_block
		(title "04192023_DAF0TMB3IC0_F0TG_MB_C_brd_V02_OCP.brd")
		(comment 1 "Grand Teton / footprints 4360-4360 of 8354")
	)
	(layers
		(0 "F.Cu" signal "TOP")
		(4 "In1.Cu" signal "GND")
		(6 "In2.Cu" signal "IN1")
		(8 "In3.Cu" signal "GND1")
		(10 "In4.Cu" signal "IN2")
		(12 "In5.Cu" signal "GND2")
		(14 "In6.Cu" signal "IN3")
		(16 "In7.Cu" signal "GND3")
		(18 "In8.Cu" signal "VCC")
		(20 "In9.Cu" signal "VCC1")
		(22 "In10.Cu" signal "GND4")
		(24 "In11.Cu" signal "IN4")
		(26 "In12.Cu" signal "GND5")
		(28 "In13.Cu" signal "IN5")
		(30 "In14.Cu" signal "GND6")
		(32 "In15.Cu" signal "IN6")
		(34 "In16.Cu" signal "GND7")
		(2 "B.Cu" signal "BOTTOM")
		(9 "F.Adhes" user "F.Adhesive")
		(11 "B.Adhes" user "B.Adhesive")
		(13 "F.Paste" user "Package Geometry/Pastemask Top")
		(15 "B.Paste" user "Package Geometry/Pastemask Bottom")
		(5 "F.SilkS" user "Ref Des/Silkscreen Top")
		(7 "B.SilkS" user "Ref Des/Silkscreen Bottom")
		(1 "F.Mask" user "Board Geometry/Soldermask Top")
		(3 "B.Mask" user "Board Geometry/Soldermask Bottom")
		(17 "Dwgs.User" user "User.Drawings")
		(19 "Cmts.User" user "User.Comments")
		(21 "Eco1.User" user "User.Eco1")
		(23 "Eco2.User" user "User.Eco2")
		(25 "Edge.Cuts" user "Board Geometry/Outline")
		(27 "Margin" user)
		(31 "F.CrtYd" user "Package Geometry/Place Bound Top")
		(29 "B.CrtYd" user "Package Geometry/Place Bound Bottom")
		(35 "F.Fab" user "Ref Des/Assembly Top")
		(33 "B.Fab" user "Ref Des/Assembly Bottom")
	)
	(footprint ""
		(layer "F.Cu")
		(at 234.739688 -156.314648 180)
		(property "Reference" "U14"
			(at -3.930904 -1.816608 0)
			(unlocked yes)
			(layer "F.SilkS")
			(effects
				(font
					(size 0.7874 0.5842)
					(thickness 0.1524)
				)
				(justify left)
			)
		)
		(property "Value" ""
			(at 0 0 180)
			(layer "F.Fab")
			(effects
				(font
					(size 1.27 1.27)
				)
			)
		)
		(duplicate_pad_numbers_are_jumpers no)
		(fp_line
			(start 1.0414 1.575054)
			(end -1.0414 1.575054)
			(stroke
				(width 0.1524)
				(type default)
			)
			(layer "F.SilkS")
		)
		(fp_line
			(start 1.0414 -1.575054)
			(end 1.0414 1.575054)
			(stroke
				(width 0.1524)
				(type default)
			)
			(layer "F.SilkS")
		)
		(fp_line
			(start 0.254 -1.575054)
			(end 1.0414 -1.575054)
			(stroke
				(width 0.1524)
				(type default)
			)
			(layer "F.SilkS")
		)
		(fp_line
			(start 0.2286 -1.575054)
			(end 0 -1.272032)
			(stroke
				(width 0.1524)
				(type default)
			)
			(layer "F.SilkS")
		)
		(fp_line
			(start 0 -1.272032)
			(end -0.254 -1.575054)
			(stroke
				(width 0.1524)
				(type default)
			)
			(layer "F.SilkS")
		)
		(fp_line
			(start -1.0414 1.575054)
			(end -1.0414 -1.575054)
			(stroke
				(width 0.1524)
				(type default)
			)
			(layer "F.SilkS")
		)
		(fp_line
			(start -1.0414 -1.575054)
			(end -0.254 -1.575054)
			(stroke
				(width 0.1524)
				(type default)
			)
			(layer "F.SilkS")
		)
		(fp_poly
			(pts
				(xy -3.916172 -1.656588) (xy -3.32105 -2.479802) (xy -2.79527 -1.472946)
			)
			(stroke
				(width 0)
				(type default)
			)
			(fill yes)
			(layer "F.SilkS")
		)
		(fp_line
			(start 2.5654 1.2192)
			(end 1.4478 1.2192)
			(stroke
				(width 0.1)
				(type default)
			)
			(layer "F.Fab")
		)
		(fp_line
			(start 2.5654 -1.2192)
			(end 2.5654 1.2192)
			(stroke
				(width 0.1)
				(type default)
			)
			(layer "F.Fab")
		)
		(fp_line
			(start 1.4478 1.5748)
			(end -1.4478 1.5748)
			(stroke
				(width 0.1)
				(type default)
			)
			(layer "F.Fab")
		)
		(fp_line
			(start 1.4478 1.2192)
			(end 1.4478 1.5748)
			(stroke
				(width 0.1)
				(type default)
			)
			(layer "F.Fab")
		)
		(fp_line
			(start 1.4478 -1.2192)
			(end 2.5654 -1.2192)
			(stroke
				(width 0.1)
				(type default)
			)
			(layer "F.Fab")
		)
		(fp_line
			(start 1.4478 -1.5748)
			(end 1.4478 -1.2192)
			(stroke
				(width 0.1)
				(type default)
			)
			(layer "F.Fab")
		)
		(fp_line
			(start -1.4478 1.5748)
			(end -1.4478 1.2192)
			(stroke
				(width 0.1)
				(type default)
			)
			(layer "F.Fab")
		)
		(fp_line
			(start -1.4478 1.2192)
			(end -2.5654 1.2192)
			(stroke
				(width 0.1)
				(type default)
			)
			(layer "F.Fab")
		)
		(fp_line
			(start -1.4478 -1.2192)
			(end -1.4478 -1.5748)
			(stroke
				(width 0.1)
				(type default)
			)
			(layer "F.Fab")
		)
		(fp_line
			(start -1.4478 -1.5748)
			(end 1.4478 -1.5748)
			(stroke
				(width 0.1)
				(type default)
			)
			(layer "F.Fab")
		)
		(fp_line
			(start -2.5654 1.2192)
			(end -2.5654 -1.2192)
			(stroke
				(width 0.1)
				(type default)
			)
			(layer "F.Fab")
		)
		(fp_line
			(start -2.5654 -1.2192)
			(end -1.4478 -1.2192)
			(stroke
				(width 0.1)
				(type default)
			)
			(layer "F.Fab")
		)
		(fp_poly
			(pts
				(xy -2.710688 -0.975106) (xy -3.726688 -1.483106) (xy -3.726688 -0.467106)
			)
			(stroke
				(width 0)
				(type default)
			)
			(fill yes)
			(layer "F.Fab")
		)
		(pad "1" smd rect
			(at -1.849882 -0.975106 90)
			(size 0.3556 1.3208)
			(layers "F.Cu" "F.Mask" "F.Paste")
			(net "JTAG_CPU0_TDO_CPU1_TDI")
		)
		(pad "2" smd rect
			(at -1.849882 -0.32512 90)
			(size 0.3556 1.3208)
			(layers "F.Cu" "F.Mask" "F.Paste")
			(net "JTAG_CPU1_R_TDI")
		)
		(pad "3" smd rect
			(at -1.849882 0.32512 90)
			(size 0.3556 1.3208)
			(layers "F.Cu" "F.Mask" "F.Paste")
			(net "FM_PLD_CPU1_PRSNT_HDT_N")
		)
		(pad "4" smd rect
			(at -1.849882 0.975106 90)
			(size 0.3556 1.3208)
			(layers "F.Cu" "F.Mask" "F.Paste")
			(net "GND")
		)
		(pad "5" smd rect
			(at 1.849882 0.975106 90)
			(size 0.3556 1.3208)
			(layers "F.Cu" "F.Mask" "F.Paste")
			(net "JTAG_CPU0_TDO_CPU1_TDI")
		)
		(pad "6" smd rect
			(at 1.849882 0.32512 90)
			(size 0.3556 1.3208)
			(layers "F.Cu" "F.Mask" "F.Paste")
			(net "JTAG_CPU1_BYPASS")
		)
		(pad "7" smd rect
			(at 1.849882 -0.32512 90)
			(size 0.3556 1.3208)
			(layers "F.Cu" "F.Mask" "F.Paste")
			(net "CPU1_HDT_BYPASS_SEL")
		)
		(pad "8" smd rect
			(at 1.849882 -0.975106 90)
			(size 0.3556 1.3208)
			(layers "F.Cu" "F.Mask" "F.Paste")
			(net "PVDD18_S5_P0")
		)
	)
)
